# S9S_MB_2U (Grand Teton) — schematic netlist excerpt (pin names and nets, part order shuffled) for the footprints in the layout excerpt that follows; sources: Cadence DE-HDL packaged netlist, KiCad conversion of 03242023_DA0F0TMBIJ0_F0T_Motherboard_J_brd_V01_OCP.brd

PC461  Q_CAPP  270UF 16V 20% OSCON  pkg THLF  page 293 : A = SW_P12V_PVCCINFAON_CPU1_FLT ; B = GND
PC335  Q_CAP  10UF 6.3V 20% X6S  pkg C0402  page 266 : A = PVCCIN_CPU0_VREF ; B = GND
R3600  Q_RES  33.2 1% CHIP  pkg 0402LF  page 171 : A = SMB_INA230_1_3V3AUX_SCL_R ; B = SMB_INA230_1_3V3AUX_SCL_R1

(kicad_pcb
	(version 20260206)
	(generator "pcbnew")
	(generator_version "10.0")
	(general
		(thickness 1.6)
		(legacy_teardrops no)
	)
	(paper "A4")
	(title_block
		(title "03242023_DA0F0TMBIJ0_F0T_Motherboard_J_brd_V01_OCP.brd")
		(comment 1 "Grand Teton / footprints 970-972 of 6105")
	)
	(layers
		(0 "F.Cu" signal "TOP")
		(4 "In1.Cu" signal "GND")
		(6 "In2.Cu" signal "IN1")
		(8 "In3.Cu" signal "GND1")
		(10 "In4.Cu" signal "IN2")
		(12 "In5.Cu" signal "GND2")
		(14 "In6.Cu" signal "IN3")
		(16 "In7.Cu" signal "GND3")
		(18 "In8.Cu" signal "VCC")
		(20 "In9.Cu" signal "VCC1")
		(22 "In10.Cu" signal "GND4")
		(24 "In11.Cu" signal "IN4")
		(26 "In12.Cu" signal "GND5")
		(28 "In13.Cu" signal "IN5")
		(30 "In14.Cu" signal "GND6")
		(32 "In15.Cu" signal "IN6")
		(34 "In16.Cu" signal "GND7")
		(2 "B.Cu" signal "BOTTOM")
		(9 "F.Adhes" user "F.Adhesive")
		(11 "B.Adhes" user "B.Adhesive")
		(13 "F.Paste" user "Package Geometry/Pastemask Top")
		(15 "B.Paste" user "Package Geometry/Pastemask Bottom")
		(5 "F.SilkS" user "Ref Des/Silkscreen Top")
		(7 "B.SilkS" user "Ref Des/Silkscreen Bottom")
		(1 "F.Mask" user "Board Geometry/Soldermask Top")
		(3 "B.Mask" user "Board Geometry/Soldermask Bottom")
		(17 "Dwgs.User" user "User.Drawings")
		(19 "Cmts.User" user "User.Comments")
		(21 "Eco1.User" user "User.Eco1")
		(23 "Eco2.User" user "User.Eco2")
		(25 "Edge.Cuts" user "Board Geometry/Outline")
		(27 "Margin" user)
		(31 "F.CrtYd" user "Package Geometry/Place Bound Top")
		(29 "B.CrtYd" user "Package Geometry/Place Bound Bottom")
		(35 "F.Fab" user "Ref Des/Assembly Top")
		(33 "B.Fab" user "Ref Des/Assembly Bottom")
	)
	(footprint ""
		(layer "F.Cu")
		(at 362.546646 -365.287814 90)
		(property "Reference" "PC335"
			(at 0 0 90)
			(layer "F.SilkS")
			(hide yes)
			(effects
				(font
					(size 1.27 1.27)
				)
			)
		)
		(property "Value" ""
			(at 0 0 90)
			(layer "F.Fab")
			(effects
				(font
					(size 1.27 1.27)
				)
			)
		)
		(duplicate_pad_numbers_are_jumpers no)
		(fp_line
			(start 0.7874 -0.4064)
			(end 0.7874 0.4064)
			(stroke
				(width 0.1524)
				(type default)
			)
			(layer "F.SilkS")
		)
		(fp_line
			(start -0.7874 -0.4064)
			(end 0.7874 -0.4064)
			(stroke
				(width 0.1524)
				(type default)
			)
			(layer "F.SilkS")
		)
		(fp_line
			(start 0.7874 0.4064)
			(end -0.7874 0.4064)
			(stroke
				(width 0.1524)
				(type default)
			)
			(layer "F.SilkS")
		)
		(fp_line
			(start -0.7874 0.4064)
			(end -0.7874 -0.4064)
			(stroke
				(width 0.1524)
				(type default)
			)
			(layer "F.SilkS")
		)
		(fp_line
			(start -0.12065 -0.305054)
			(end -0.12065 -0.2794)
			(stroke
				(width 0.1)
				(type default)
			)
			(layer "F.Fab")
		)
		(fp_line
			(start -0.67945 -0.305054)
			(end -0.12065 -0.305054)
			(stroke
				(width 0.1)
				(type default)
			)
			(layer "F.Fab")
		)
		(fp_line
			(start 0.67945 -0.3048)
			(end 0.67945 0.3048)
			(stroke
				(width 0.1)
				(type default)
			)
			(layer "F.Fab")
		)
		(fp_line
			(start 0.12065 -0.3048)
			(end 0.67945 -0.3048)
			(stroke
				(width 0.1)
				(type default)
			)
			(layer "F.Fab")
		)
		(fp_line
			(start 0.12065 -0.2794)
			(end 0.12065 -0.3048)
			(stroke
				(width 0.1)
				(type default)
			)
			(layer "F.Fab")
		)
		(fp_line
			(start -0.12065 -0.2794)
			(end 0.12065 -0.2794)
			(stroke
				(width 0.1)
				(type default)
			)
			(layer "F.Fab")
		)
		(fp_line
			(start 0.120396 0.2794)
			(end -0.12065 0.2794)
			(stroke
				(width 0.1)
				(type default)
			)
			(layer "F.Fab")
		)
		(fp_line
			(start -0.12065 0.2794)
			(end -0.12065 0.3048)
			(stroke
				(width 0.1)
				(type default)
			)
			(layer "F.Fab")
		)
		(fp_line
			(start 0.67945 0.3048)
			(end 0.120396 0.3048)
			(stroke
				(width 0.1)
				(type default)
			)
			(layer "F.Fab")
		)
		(fp_line
			(start 0.120396 0.3048)
			(end 0.120396 0.2794)
			(stroke
				(width 0.1)
				(type default)
			)
			(layer "F.Fab")
		)
		(fp_line
			(start -0.12065 0.3048)
			(end -0.67945 0.3048)
			(stroke
				(width 0.1)
				(type default)
			)
			(layer "F.Fab")
		)
		(fp_line
			(start -0.67945 0.3048)
			(end -0.67945 -0.305054)
			(stroke
				(width 0.1)
				(type default)
			)
			(layer "F.Fab")
		)
		(pad "1" smd circle
			(at -0.40005 0 90)
			(size 0 0)
			(layers "F.Cu" "F.Mask" "F.Paste")
			(net "PVCCIN_CPU0_VREF")
		)
		(pad "2" smd circle
			(at 0.40005 0 90)
			(size 0 0)
			(layers "F.Cu" "F.Mask" "F.Paste")
			(net "GND")
		)
	)
	(footprint ""
		(layer "F.Cu")
		(at 44.36999 -164.39134)
		(property "Reference" "PC461"
			(at 0 0 0)
			(layer "F.SilkS")
			(hide yes)
			(effects
				(font
					(size 1.27 1.27)
				)
			)
		)
		(property "Value" ""
			(at 0 0 0)
			(layer "F.Fab")
			(effects
				(font
					(size 1.27 1.27)
				)
			)
		)
		(duplicate_pad_numbers_are_jumpers no)
		(fp_line
			(start -3.400044 1.249934)
			(end 3.400044 1.249934)
			(stroke
				(width 0.1524)
				(type default)
			)
			(layer "F.SilkS")
		)
		(fp_circle
			(center 0 1.249934)
			(end 3.400044 1.249934)
			(stroke
				(width 0.1524)
				(type default)
			)
			(fill no)
			(layer "F.SilkS")
		)
		(fp_poly
			(pts
				(arc
					(start -3.400044 1.249934)
					(mid 0 4.649978)
					(end 3.400044 1.249934)
				)
			)
			(stroke
				(width 0)
				(type default)
			)
			(fill yes)
			(layer "F.SilkS")
		)
		(fp_circle
			(center 0 1.249934)
			(end 3.400044 1.249934)
			(stroke
				(width 0.1)
				(type default)
			)
			(fill no)
			(layer "F.Fab")
		)
		(pad "1" thru_hole rect
			(at 0 0)
			(size 1.524 1.524)
			(drill 1.016)
			(layers "*.Cu" "*.Mask")
			(remove_unused_layers no)
			(net "SW_P12V_PVCCINFAON_CPU1_FLT")
			(clearance 0)
			(padstack
				(mode front_inner_back)
				(layer "Inner"
					(shape circle)
					(size 1.524 1.524)
					(clearance 0)
				)
				(layer "B.Cu"
					(shape rect)
					(size 1.524 1.524)
					(clearance 0)
				)
			)
		)
		(pad "2" thru_hole circle
			(at 0 2.500122)
			(size 1.524 1.524)
			(drill 1.016)
			(layers "*.Cu" "*.Mask")
			(remove_unused_layers no)
			(net "GND")
			(clearance 0)
		)
	)
	(footprint ""
		(layer "F.Cu")
		(at 445.19088 -97.269808 180)
		(property "Reference" "R3600"
			(at 0 0 180)
			(layer "F.SilkS")
			(hide yes)
			(effects
				(font
					(size 1.27 1.27)
				)
			)
		)
		(property "Value" ""
			(at 0 0 180)
			(layer "F.Fab")
			(effects
				(font
					(size 1.27 1.27)
				)
			)
		)
		(duplicate_pad_numbers_are_jumpers no)
		(fp_line
			(start 0.7874 0.4064)
			(end -0.7874 0.4064)
			(stroke
				(width 0.1524)
				(type default)
			)
			(layer "F.SilkS")
		)
		(fp_line
			(start 0.7874 -0.4064)
			(end 0.7874 0.4064)
			(stroke
				(width 0.1524)
				(type default)
			)
			(layer "F.SilkS")
		)
		(fp_line
			(start -0.7874 0.4064)
			(end -0.7874 -0.4064)
			(stroke
				(width 0.1524)
				(type default)
			)
			(layer "F.SilkS")
		)
		(fp_line
			(start -0.7874 -0.4064)
			(end 0.7874 -0.4064)
			(stroke
				(width 0.1524)
				(type default)
			)
			(layer "F.SilkS")
		)
		(fp_line
			(start 0.67945 0.3048)
			(end 0.120396 0.3048)
			(stroke
				(width 0.1)
				(type default)
			)
			(layer "F.Fab")
		)
		(fp_line
			(start 0.67945 -0.3048)
			(end 0.67945 0.3048)
			(stroke
				(width 0.1)
				(type default)
			)
			(layer "F.Fab")
		)
		(fp_line
			(start 0.12065 -0.2794)
			(end 0.12065 -0.3048)
			(stroke
				(width 0.1)
				(type default)
			)
			(layer "F.Fab")
		)
		(fp_line
			(start 0.12065 -0.3048)
			(end 0.67945 -0.3048)
			(stroke
				(width 0.1)
				(type default)
			)
			(layer "F.Fab")
		)
		(fp_line
			(start 0.120396 0.3048)
			(end 0.120396 0.2794)
			(stroke
				(width 0.1)
				(type default)
			)
			(layer "F.Fab")
		)
		(fp_line
			(start 0.120396 0.2794)
			(end -0.12065 0.2794)
			(stroke
				(width 0.1)
				(type default)
			)
			(layer "F.Fab")
		)
		(fp_line
			(start -0.12065 0.3048)
			(end -0.67945 0.3048)
			(stroke
				(width 0.1)
				(type default)
			)
			(layer "F.Fab")
		)
		(fp_line
			(start -0.12065 0.2794)
			(end -0.12065 0.3048)
			(stroke
				(width 0.1)
				(type default)
			)
			(layer "F.Fab")
		)
		(fp_line
			(start -0.12065 -0.2794)
			(end 0.12065 -0.2794)
			(stroke
				(width 0.1)
				(type default)
			)
			(layer "F.Fab")
		)
		(fp_line
			(start -0.12065 -0.305054)
			(end -0.12065 -0.2794)
			(stroke
				(width 0.1)
				(type default)
			)
			(layer "F.Fab")
		)
		(fp_line
			(start -0.67945 0.3048)
			(end -0.67945 -0.305054)
			(stroke
				(width 0.1)
				(type default)
			)
			(layer "F.Fab")
		)
		(fp_line
			(start -0.67945 -0.305054)
			(end -0.12065 -0.305054)
			(stroke
				(width 0.1)
				(type default)
			)
			(layer "F.Fab")
		)
		(pad "1" smd circle
			(at -0.40005 0 180)
			(size 0 0)
			(layers "F.Cu" "F.Mask" "F.Paste")
			(net "SMB_INA230_1_3V3AUX_SCL_R")
		)
		(pad "2" smd circle
			(at 0.40005 0 180)
			(size 0 0)
			(layers "F.Cu" "F.Mask" "F.Paste")
			(net "SMB_INA230_1_3V3AUX_SCL_R1")
		)
	)
)
